(kicad_pcb
	(version 20241229)
	(generator "pcbnew")
	(generator_version "9.0")
	(general
		(thickness 1.599998)
		(legacy_teardrops no)
	)
	(paper "A4")
	(title_block
		(date "2023-02-12")
		(rev "1.1.5")
		(comment 9 "footprints 450-456 of 473")
	)
	(layers
		(0 "F.Cu" signal)
		(4 "In1.Cu" power "In1.GND")
		(6 "In2.Cu" signal)
		(8 "In3.Cu" power "In3.GND")
		(10 "In4.Cu" power "In4.VCC")
		(12 "In5.Cu" signal)
		(14 "In6.Cu" power "In6.VCC")
		(2 "B.Cu" signal)
		(9 "F.Adhes" user "F.Adhesive")
		(11 "B.Adhes" user "B.Adhesive")
		(13 "F.Paste" user)
		(15 "B.Paste" user)
		(5 "F.SilkS" user "F.Silkscreen")
		(7 "B.SilkS" user "B.Silkscreen")
		(1 "F.Mask" user)
		(3 "B.Mask" user)
		(17 "Dwgs.User" user "User.Drawings")
		(19 "Cmts.User" user "User.Comments")
		(21 "Eco1.User" user "User.Eco1")
		(23 "Eco2.User" user "User.Eco2")
		(25 "Edge.Cuts" user)
		(27 "Margin" user)
		(31 "F.CrtYd" user "F.Courtyard")
		(29 "B.CrtYd" user "B.Courtyard")
		(35 "F.Fab" user)
		(33 "B.Fab" user)
	)
	(footprint "antmicro-footprints:R_0402_1005Metric"
		(layer "B.Cu")
		(at 208.306328 106.480008 -90)
		(descr "Resistor SMD 0402")
		(tags "resistor SMD 0402")
		(property "Reference" "R92"
			(at -0.980008 -1.293672 90)
			(layer "B.SilkS")
			(effects
				(font
					(size 0.7 0.7)
					(thickness 0.15)
				)
				(justify left bottom mirror)
			)
		)
		(property "Value" "R_2k2_0402"
			(at 0 -1.4 90)
			(layer "B.Fab")
			(effects
				(font
					(size 0.7 0.7)
					(thickness 0.15)
				)
				(justify left bottom mirror)
			)
		)
		(property "Description" "2k2 resistor in 0402 package with 1% tolerance"
			(at 0 0 270)
			(layer "F.Fab")
			(hide yes)
			(effects
				(font
					(size 1.27 1.27)
					(thickness 0.15)
				)
			)
		)
		(property "Author" "Antmicro"
			(at 101.82632 314.786336 0)
			(layer "B.Fab")
			(hide yes)
			(effects
				(font
					(size 1 1)
					(thickness 0.15)
				)
				(justify mirror)
			)
		)
		(property "License" "Apache-2.0"
			(at 101.82632 314.786336 0)
			(layer "B.Fab")
			(hide yes)
			(effects
				(font
					(size 1 1)
					(thickness 0.15)
				)
				(justify mirror)
			)
		)
		(property "MPN" "CR0402-FX-2201GLF"
			(at 101.82632 314.786336 0)
			(layer "B.Fab")
			(hide yes)
			(effects
				(font
					(size 1 1)
					(thickness 0.15)
				)
				(justify mirror)
			)
		)
		(property "Manufacturer" "Bourns"
			(at 101.82632 314.786336 0)
			(layer "B.Fab")
			(hide yes)
			(effects
				(font
					(size 1 1)
					(thickness 0.15)
				)
				(justify mirror)
			)
		)
		(property "Tolerance" "1%"
			(at 101.82632 314.786336 0)
			(layer "B.Fab")
			(hide yes)
			(effects
				(font
					(size 1 1)
					(thickness 0.15)
				)
				(justify mirror)
			)
		)
		(property "Val" "2k2"
			(at 101.82632 314.786336 0)
			(layer "B.Fab")
			(hide yes)
			(effects
				(font
					(size 1 1)
					(thickness 0.15)
				)
				(justify mirror)
			)
		)
		(sheetname "Ethernet")
		(sheetfile "ethernet.kicad_sch")
		(attr exclude_from_pos_files exclude_from_bom dnp)
		(fp_rect
			(start -0.93 0.47)
			(end 0.93 -0.47)
			(stroke
				(width 0.05)
				(type solid)
			)
			(fill no)
			(layer "B.CrtYd")
		)
		(fp_rect
			(start -0.5 0.25)
			(end 0.5 -0.25)
			(stroke
				(width 0.15)
				(type solid)
			)
			(fill no)
			(layer "B.Fab")
		)
		(pad "1" smd roundrect
			(at -0.485 0 270)
			(size 0.59 0.64)
			(layers "B.Cu" "B.Mask" "B.Paste")
			(roundrect_rratio 0.25)
			(net 13 "LED_SPD")
			(pintype "passive")
		)
		(pad "2" smd roundrect
			(at 0.485 0 270)
			(size 0.59 0.64)
			(layers "B.Cu" "B.Mask" "B.Paste")
			(roundrect_rratio 0.25)
			(net 5 "GND")
			(pintype "passive")
		)
	)
	(footprint "antmicro-footprints:R_0402_1005Metric"
		(layer "B.Cu")
		(at 208.306328 102.070008 90)
		(descr "Resistor SMD 0402")
		(tags "resistor SMD 0402")
		(property "Reference" "R93"
			(at 1.070008 1.293672 270)
			(layer "B.SilkS")
			(effects
				(font
					(size 0.7 0.7)
					(thickness 0.15)
				)
				(justify left bottom mirror)
			)
		)
		(property "Value" "R_2k2_0402"
			(at 0 -1.4 270)
			(layer "B.Fab")
			(effects
				(font
					(size 0.7 0.7)
					(thickness 0.15)
				)
				(justify left bottom mirror)
			)
		)
		(property "Description" "2k2 resistor in 0402 package with 1% tolerance"
			(at 0 0 90)
			(layer "F.Fab")
			(hide yes)
			(effects
				(font
					(size 1.27 1.27)
					(thickness 0.15)
				)
			)
		)
		(property "Author" "Antmicro"
			(at 310.376336 -106.23632 0)
			(layer "B.Fab")
			(hide yes)
			(effects
				(font
					(size 1 1)
					(thickness 0.15)
				)
				(justify mirror)
			)
		)
		(property "License" "Apache-2.0"
			(at 310.376336 -106.23632 0)
			(layer "B.Fab")
			(hide yes)
			(effects
				(font
					(size 1 1)
					(thickness 0.15)
				)
				(justify mirror)
			)
		)
		(property "MPN" "CR0402-FX-2201GLF"
			(at 310.376336 -106.23632 0)
			(layer "B.Fab")
			(hide yes)
			(effects
				(font
					(size 1 1)
					(thickness 0.15)
				)
				(justify mirror)
			)
		)
		(property "Manufacturer" "Bourns"
			(at 310.376336 -106.23632 0)
			(layer "B.Fab")
			(hide yes)
			(effects
				(font
					(size 1 1)
					(thickness 0.15)
				)
				(justify mirror)
			)
		)
		(property "Tolerance" "1%"
			(at 310.376336 -106.23632 0)
			(layer "B.Fab")
			(hide yes)
			(effects
				(font
					(size 1 1)
					(thickness 0.15)
				)
				(justify mirror)
			)
		)
		(property "Val" "2k2"
			(at 310.376336 -106.23632 0)
			(layer "B.Fab")
			(hide yes)
			(effects
				(font
					(size 1 1)
					(thickness 0.15)
				)
				(justify mirror)
			)
		)
		(sheetname "Ethernet")
		(sheetfile "ethernet.kicad_sch")
		(attr exclude_from_pos_files exclude_from_bom dnp)
		(fp_rect
			(start -0.93 0.47)
			(end 0.93 -0.47)
			(stroke
				(width 0.05)
				(type solid)
			)
			(fill no)
			(layer "B.CrtYd")
		)
		(fp_rect
			(start -0.5 0.25)
			(end 0.5 -0.25)
			(stroke
				(width 0.15)
				(type solid)
			)
			(fill no)
			(layer "B.Fab")
		)
		(pad "1" smd roundrect
			(at -0.485 0 90)
			(size 0.59 0.64)
			(layers "B.Cu" "B.Mask" "B.Paste")
			(roundrect_rratio 0.25)
			(net 12 "LED_LINK")
			(pintype "passive")
		)
		(pad "2" smd roundrect
			(at 0.485 0 90)
			(size 0.59 0.64)
			(layers "B.Cu" "B.Mask" "B.Paste")
			(roundrect_rratio 0.25)
			(net 5 "GND")
			(pintype "passive")
		)
	)
	(footprint "antmicro-footprints:R_0402_1005Metric"
		(layer "B.Cu")
		(at 198.376328 101.660008)
		(descr "Resistor SMD 0402")
		(tags "resistor SMD 0402")
		(property "Reference" "R91"
			(at -0.776328 0.339992 180)
			(layer "B.SilkS")
			(effects
				(font
					(size 0.7 0.7)
					(thickness 0.15)
				)
				(justify left bottom mirror)
			)
		)
		(property "Value" "R_2k2_0402"
			(at 0 -1.4 180)
			(layer "B.Fab")
			(effects
				(font
					(size 0.7 0.7)
					(thickness 0.15)
				)
				(justify left bottom mirror)
			)
		)
		(property "Description" "2k2 resistor in 0402 package with 1% tolerance"
			(at 0 0 0)
			(layer "F.Fab")
			(hide yes)
			(effects
				(font
					(size 1.27 1.27)
					(thickness 0.15)
				)
			)
		)
		(property "Author" "Antmicro"
			(at 0 0 0)
			(layer "B.Fab")
			(hide yes)
			(effects
				(font
					(size 1 1)
					(thickness 0.15)
				)
				(justify mirror)
			)
		)
		(property "License" "Apache-2.0"
			(at 0 0 0)
			(layer "B.Fab")
			(hide yes)
			(effects
				(font
					(size 1 1)
					(thickness 0.15)
				)
				(justify mirror)
			)
		)
		(property "MPN" "CR0402-FX-2201GLF"
			(at 0 0 0)
			(layer "B.Fab")
			(hide yes)
			(effects
				(font
					(size 1 1)
					(thickness 0.15)
				)
				(justify mirror)
			)
		)
		(property "Manufacturer" "Bourns"
			(at 0 0 0)
			(layer "B.Fab")
			(hide yes)
			(effects
				(font
					(size 1 1)
					(thickness 0.15)
				)
				(justify mirror)
			)
		)
		(property "Tolerance" "1%"
			(at 0 0 0)
			(layer "B.Fab")
			(hide yes)
			(effects
				(font
					(size 1 1)
					(thickness 0.15)
				)
				(justify mirror)
			)
		)
		(property "Val" "2k2"
			(at 0 0 0)
			(layer "B.Fab")
			(hide yes)
			(effects
				(font
					(size 1 1)
					(thickness 0.15)
				)
				(justify mirror)
			)
		)
		(sheetname "Ethernet")
		(sheetfile "ethernet.kicad_sch")
		(attr exclude_from_pos_files exclude_from_bom dnp)
		(fp_rect
			(start -0.93 0.47)
			(end 0.93 -0.47)
			(stroke
				(width 0.05)
				(type solid)
			)
			(fill no)
			(layer "B.CrtYd")
		)
		(fp_rect
			(start -0.5 0.25)
			(end 0.5 -0.25)
			(stroke
				(width 0.15)
				(type solid)
			)
			(fill no)
			(layer "B.Fab")
		)
		(pad "1" smd roundrect
			(at -0.485 0)
			(size 0.59 0.64)
			(layers "B.Cu" "B.Mask" "B.Paste")
			(roundrect_rratio 0.25)
			(net 26 "ETH_REF_CLK")
			(pintype "passive")
		)
		(pad "2" smd roundrect
			(at 0.485 0)
			(size 0.59 0.64)
			(layers "B.Cu" "B.Mask" "B.Paste")
			(roundrect_rratio 0.25)
			(net 5 "GND")
			(pintype "passive")
		)
	)
	(footprint "antmicro-footprints:R_0402_1005Metric"
		(layer "B.Cu")
		(at 193.486328 97.210008 180)
		(descr "Resistor SMD 0402")
		(tags "resistor SMD 0402")
		(property "Reference" "R89"
			(at 0.786328 -0.389992 0)
			(layer "B.SilkS")
			(effects
				(font
					(size 0.7 0.7)
					(thickness 0.15)
				)
				(justify left bottom mirror)
			)
		)
		(property "Value" "R_2k2_0402"
			(at 0 -1.4 0)
			(layer "B.Fab")
			(effects
				(font
					(size 0.7 0.7)
					(thickness 0.15)
				)
				(justify left bottom mirror)
			)
		)
		(property "Description" "2k2 resistor in 0402 package with 1% tolerance"
			(at 0 0 180)
			(layer "F.Fab")
			(hide yes)
			(effects
				(font
					(size 1.27 1.27)
					(thickness 0.15)
				)
			)
		)
		(property "Author" "Antmicro"
			(at 386.972656 194.420016 0)
			(layer "B.Fab")
			(hide yes)
			(effects
				(font
					(size 1 1)
					(thickness 0.15)
				)
				(justify mirror)
			)
		)
		(property "License" "Apache-2.0"
			(at 386.972656 194.420016 0)
			(layer "B.Fab")
			(hide yes)
			(effects
				(font
					(size 1 1)
					(thickness 0.15)
				)
				(justify mirror)
			)
		)
		(property "MPN" "CR0402-FX-2201GLF"
			(at 386.972656 194.420016 0)
			(layer "B.Fab")
			(hide yes)
			(effects
				(font
					(size 1 1)
					(thickness 0.15)
				)
				(justify mirror)
			)
		)
		(property "Manufacturer" "Bourns"
			(at 386.972656 194.420016 0)
			(layer "B.Fab")
			(hide yes)
			(effects
				(font
					(size 1 1)
					(thickness 0.15)
				)
				(justify mirror)
			)
		)
		(property "Tolerance" "1%"
			(at 386.972656 194.420016 0)
			(layer "B.Fab")
			(hide yes)
			(effects
				(font
					(size 1 1)
					(thickness 0.15)
				)
				(justify mirror)
			)
		)
		(property "Val" "2k2"
			(at 386.972656 194.420016 0)
			(layer "B.Fab")
			(hide yes)
			(effects
				(font
					(size 1 1)
					(thickness 0.15)
				)
				(justify mirror)
			)
		)
		(sheetname "Ethernet")
		(sheetfile "ethernet.kicad_sch")
		(attr smd)
		(fp_rect
			(start -0.93 0.47)
			(end 0.93 -0.47)
			(stroke
				(width 0.05)
				(type solid)
			)
			(fill no)
			(layer "B.CrtYd")
		)
		(fp_rect
			(start -0.5 0.25)
			(end 0.5 -0.25)
			(stroke
				(width 0.15)
				(type solid)
			)
			(fill no)
			(layer "B.Fab")
		)
		(pad "1" smd roundrect
			(at -0.485 0 180)
			(size 0.59 0.64)
			(layers "B.Cu" "B.Mask" "B.Paste")
			(roundrect_rratio 0.25)
			(net 34 "ETH_RX_DV")
			(pintype "passive")
		)
		(pad "2" smd roundrect
			(at 0.485 0 180)
			(size 0.59 0.64)
			(layers "B.Cu" "B.Mask" "B.Paste")
			(roundrect_rratio 0.25)
			(net 5 "GND")
			(pintype "passive")
		)
	)
	(footprint "antmicro-footprints:C_0201"
		(layer "B.Cu")
		(at 158.796328 89.180008)
		(descr "Capacitor SMD 0201")
		(tags "capacitor SMD 0201")
		(property "Reference" "C76"
			(at 1.003672 -0.280008 180)
			(layer "B.SilkS")
			(effects
				(font
					(size 0.7 0.7)
					(thickness 0.15)
				)
				(justify left bottom mirror)
			)
		)
		(property "Value" "C_100n_0201"
			(at 0 -1.4 180)
			(layer "B.Fab")
			(effects
				(font
					(size 0.7 0.7)
					(thickness 0.15)
				)
				(justify left bottom mirror)
			)
		)
		(property "Description" " "
			(at 0 0 0)
			(layer "F.Fab")
			(hide yes)
			(effects
				(font
					(size 1.27 1.27)
					(thickness 0.15)
				)
			)
		)
		(property "Author" "Antmicro"
			(at 0 0 0)
			(layer "B.Fab")
			(hide yes)
			(effects
				(font
					(size 1 1)
					(thickness 0.15)
				)
				(justify mirror)
			)
		)
		(property "Dielectric" ""
			(at 0 0 0)
			(layer "B.Fab")
			(hide yes)
			(effects
				(font
					(size 1 1)
					(thickness 0.15)
				)
				(justify mirror)
			)
		)
		(property "License" "Apache-2.0"
			(at 0 0 0)
			(layer "B.Fab")
			(hide yes)
			(effects
				(font
					(size 1 1)
					(thickness 0.15)
				)
				(justify mirror)
			)
		)
		(property "MPN" "CC0201KRX6S5BB104"
			(at 0 0 0)
			(layer "B.Fab")
			(hide yes)
			(effects
				(font
					(size 1 1)
					(thickness 0.15)
				)
				(justify mirror)
			)
		)
		(property "Manufacturer" "Yaego"
			(at 0 0 0)
			(layer "B.Fab")
			(hide yes)
			(effects
				(font
					(size 1 1)
					(thickness 0.15)
				)
				(justify mirror)
			)
		)
		(property "Val" "100n"
			(at 0 0 0)
			(layer "B.Fab")
			(hide yes)
			(effects
				(font
					(size 1 1)
					(thickness 0.15)
				)
				(justify mirror)
			)
		)
		(property "Voltage" ""
			(at 0 0 0)
			(layer "B.Fab")
			(hide yes)
			(effects
				(font
					(size 1 1)
					(thickness 0.15)
				)
				(justify mirror)
			)
		)
		(sheetname "FPGA power")
		(sheetfile "fpga-power.kicad_sch")
		(attr smd)
		(fp_rect
			(start -0.72 0.38)
			(end 0.72 -0.38)
			(stroke
				(width 0.05)
				(type solid)
			)
			(fill no)
			(layer "B.CrtYd")
		)
		(fp_rect
			(start 0.3 -0.15)
			(end -0.301 0.149)
			(stroke
				(width 0.15)
				(type solid)
			)
			(fill no)
			(layer "B.Fab")
		)
		(pad "" smd roundrect
			(at -0.349 0.002)
			(size 0.318 0.36)
			(layers "B.Paste")
			(roundrect_rratio 0.25)
		)
		(pad "" smd roundrect
			(at 0.341 0.002)
			(size 0.318 0.36)
			(layers "B.Paste")
			(roundrect_rratio 0.25)
		)
		(pad "1" smd roundrect
			(at -0.321 0.002)
			(size 0.46 0.4)
			(layers "B.Cu" "B.Mask")
			(roundrect_rratio 0.25)
			(net 66 "VDDQ")
			(pintype "passive")
		)
		(pad "2" smd roundrect
			(at 0.32 0.002)
			(size 0.46 0.4)
			(layers "B.Cu" "B.Mask")
			(roundrect_rratio 0.25)
			(net 5 "GND")
			(pintype "passive")
		)
	)
	(footprint "antmicro-footprints:C_0201"
		(layer "B.Cu")
		(at 161.006328 94.470008)
		(descr "Capacitor SMD 0201")
		(tags "capacitor SMD 0201")
		(property "Reference" "C80"
			(at -0.506328 0.429992 180)
			(layer "B.SilkS")
			(effects
				(font
					(size 0.7 0.7)
					(thickness 0.15)
				)
				(justify left bottom mirror)
			)
		)
		(property "Value" "C_100n_0201"
			(at 0 -1.4 180)
			(layer "B.Fab")
			(effects
				(font
					(size 0.7 0.7)
					(thickness 0.15)
				)
				(justify left bottom mirror)
			)
		)
		(property "Description" " "
			(at 0 0 0)
			(layer "F.Fab")
			(hide yes)
			(effects
				(font
					(size 1.27 1.27)
					(thickness 0.15)
				)
			)
		)
		(property "Author" "Antmicro"
			(at 0 0 0)
			(layer "B.Fab")
			(hide yes)
			(effects
				(font
					(size 1 1)
					(thickness 0.15)
				)
				(justify mirror)
			)
		)
		(property "Dielectric" ""
			(at 0 0 0)
			(layer "B.Fab")
			(hide yes)
			(effects
				(font
					(size 1 1)
					(thickness 0.15)
				)
				(justify mirror)
			)
		)
		(property "License" "Apache-2.0"
			(at 0 0 0)
			(layer "B.Fab")
			(hide yes)
			(effects
				(font
					(size 1 1)
					(thickness 0.15)
				)
				(justify mirror)
			)
		)
		(property "MPN" "CC0201KRX6S5BB104"
			(at 0 0 0)
			(layer "B.Fab")
			(hide yes)
			(effects
				(font
					(size 1 1)
					(thickness 0.15)
				)
				(justify mirror)
			)
		)
		(property "Manufacturer" "Yaego"
			(at 0 0 0)
			(layer "B.Fab")
			(hide yes)
			(effects
				(font
					(size 1 1)
					(thickness 0.15)
				)
				(justify mirror)
			)
		)
		(property "Val" "100n"
			(at 0 0 0)
			(layer "B.Fab")
			(hide yes)
			(effects
				(font
					(size 1 1)
					(thickness 0.15)
				)
				(justify mirror)
			)
		)
		(property "Voltage" ""
			(at 0 0 0)
			(layer "B.Fab")
			(hide yes)
			(effects
				(font
					(size 1 1)
					(thickness 0.15)
				)
				(justify mirror)
			)
		)
		(sheetname "FPGA power")
		(sheetfile "fpga-power.kicad_sch")
		(attr smd)
		(fp_rect
			(start -0.72 0.38)
			(end 0.72 -0.38)
			(stroke
				(width 0.05)
				(type solid)
			)
			(fill no)
			(layer "B.CrtYd")
		)
		(fp_rect
			(start 0.3 -0.15)
			(end -0.301 0.149)
			(stroke
				(width 0.15)
				(type solid)
			)
			(fill no)
			(layer "B.Fab")
		)
		(pad "" smd roundrect
			(at -0.349 0.002)
			(size 0.318 0.36)
			(layers "B.Paste")
			(roundrect_rratio 0.25)
		)
		(pad "" smd roundrect
			(at 0.341 0.002)
			(size 0.318 0.36)
			(layers "B.Paste")
			(roundrect_rratio 0.25)
		)
		(pad "1" smd roundrect
			(at -0.321 0.002)
			(size 0.46 0.4)
			(layers "B.Cu" "B.Mask")
			(roundrect_rratio 0.25)
			(net 66 "VDDQ")
			(pintype "passive")
		)
		(pad "2" smd roundrect
			(at 0.32 0.002)
			(size 0.46 0.4)
			(layers "B.Cu" "B.Mask")
			(roundrect_rratio 0.25)
			(net 5 "GND")
			(pintype "passive")
		)
	)
	(footprint "antmicro-footprints:R_0402_1005Metric"
		(layer "B.Cu")
		(at 125.6 67.65 180)
		(descr "Resistor SMD 0402")
		(tags "resistor SMD 0402")
		(property "Reference" "R158"
			(at -1.4 -1.25 0)
			(layer "B.SilkS")
			(effects
				(font
					(size 0.7 0.7)
					(thickness 0.15)
				)
				(justify left bottom mirror)
			)
		)
		(property "Value" "R_0R_0402"
			(at 0 -1.4 0)
			(layer "B.Fab")
			(effects
				(font
					(size 0.7 0.7)
					(thickness 0.15)
				)
				(justify left bottom mirror)
			)
		)
		(property "Description" "0R resistor in 0402 package with unspecified tolerance"
			(at 0 0 180)
			(layer "F.Fab")
			(hide yes)
			(effects
				(font
					(size 1.27 1.27)
					(thickness 0.15)
				)
			)
		)
		(property "Author" "Antmicro"
			(at 251.2 135.3 0)
			(layer "B.Fab")
			(hide yes)
			(effects
				(font
					(size 1 1)
					(thickness 0.15)
				)
				(justify mirror)
			)
		)
		(property "Current" "1A"
			(at 251.2 135.3 0)
			(layer "B.Fab")
			(hide yes)
			(effects
				(font
					(size 1 1)
					(thickness 0.15)
				)
				(justify mirror)
			)
		)
		(property "License" "Apache-2.0"
			(at 251.2 135.3 0)
			(layer "B.Fab")
			(hide yes)
			(effects
				(font
					(size 1 1)
					(thickness 0.15)
				)
				(justify mirror)
			)
		)
		(property "MPN" "ERJ2GE0R00X"
			(at 251.2 135.3 0)
			(layer "B.Fab")
			(hide yes)
			(effects
				(font
					(size 1 1)
					(thickness 0.15)
				)
				(justify mirror)
			)
		)
		(property "Manufacturer" "Panasonic"
			(at 251.2 135.3 0)
			(layer "B.Fab")
			(hide yes)
			(effects
				(font
					(size 1 1)
					(thickness 0.15)
				)
				(justify mirror)
			)
		)
		(property "Tolerance" ""
			(at 251.2 135.3 0)
			(layer "B.Fab")
			(hide yes)
			(effects
				(font
					(size 1 1)
					(thickness 0.15)
				)
				(justify mirror)
			)
		)
		(property "Val" "0R"
			(at 251.2 135.3 0)
			(layer "B.Fab")
			(hide yes)
			(effects
				(font
					(size 1 1)
					(thickness 0.15)
				)
				(justify mirror)
			)
		)
		(sheetname "Supply")
		(sheetfile "supply.kicad_sch")
		(attr exclude_from_pos_files exclude_from_bom dnp)
		(fp_rect
			(start -0.93 0.47)
			(end 0.93 -0.47)
			(stroke
				(width 0.05)
				(type solid)
			)
			(fill no)
			(layer "B.CrtYd")
		)
		(fp_rect
			(start -0.5 0.25)
			(end 0.5 -0.25)
			(stroke
				(width 0.15)
				(type solid)
			)
			(fill no)
			(layer "B.Fab")
		)
		(pad "1" smd roundrect
			(at -0.485 0 180)
			(size 0.59 0.64)
			(layers "B.Cu" "B.Mask" "B.Paste")
			(roundrect_rratio 0.25)
			(net 643 "FPGA_AB22_BALL")
			(pintype "passive")
		)
		(pad "2" smd roundrect
			(at 0.485 0 180)
			(size 0.59 0.64)
			(layers "B.Cu" "B.Mask" "B.Paste")
			(roundrect_rratio 0.25)
			(net 238 "Net-(Q13-G)")
			(pintype "passive")
		)
	)
)
